(kicad_pcb
	(version 20260206)
	(generator "pcbnew")
	(generator_version "10.0")
	(general
		(thickness 1.6)
		(legacy_teardrops no)
	)
	(paper "A4")
	(title_block
		(title "04192023_DAF0TMB3IC0_F0TG_MB_C_brd_V02_OCP.brd")
		(comment 1 "Grand Teton / footprints 6706-6712 of 8354")
	)
	(layers
		(0 "F.Cu" signal "TOP")
		(4 "In1.Cu" signal "GND")
		(6 "In2.Cu" signal "IN1")
		(8 "In3.Cu" signal "GND1")
		(10 "In4.Cu" signal "IN2")
		(12 "In5.Cu" signal "GND2")
		(14 "In6.Cu" signal "IN3")
		(16 "In7.Cu" signal "GND3")
		(18 "In8.Cu" signal "VCC")
		(20 "In9.Cu" signal "VCC1")
		(22 "In10.Cu" signal "GND4")
		(24 "In11.Cu" signal "IN4")
		(26 "In12.Cu" signal "GND5")
		(28 "In13.Cu" signal "IN5")
		(30 "In14.Cu" signal "GND6")
		(32 "In15.Cu" signal "IN6")
		(34 "In16.Cu" signal "GND7")
		(2 "B.Cu" signal "BOTTOM")
		(9 "F.Adhes" user "F.Adhesive")
		(11 "B.Adhes" user "B.Adhesive")
		(13 "F.Paste" user "Package Geometry/Pastemask Top")
		(15 "B.Paste" user "Package Geometry/Pastemask Bottom")
		(5 "F.SilkS" user "Ref Des/Silkscreen Top")
		(7 "B.SilkS" user "Ref Des/Silkscreen Bottom")
		(1 "F.Mask" user "Board Geometry/Soldermask Top")
		(3 "B.Mask" user "Board Geometry/Soldermask Bottom")
		(17 "Dwgs.User" user "User.Drawings")
		(19 "Cmts.User" user "User.Comments")
		(21 "Eco1.User" user "User.Eco1")
		(23 "Eco2.User" user "User.Eco2")
		(25 "Edge.Cuts" user "Board Geometry/Outline")
		(27 "Margin" user)
		(31 "F.CrtYd" user "Package Geometry/Place Bound Top")
		(29 "B.CrtYd" user "Package Geometry/Place Bound Bottom")
		(35 "F.Fab" user "Ref Des/Assembly Top")
		(33 "B.Fab" user "Ref Des/Assembly Bottom")
	)
	(footprint ""
		(layer "B.Cu")
		(at 76.753974 -186.316112 90)
		(property "Reference" "PC280_2"
			(at 0 0 90)
			(layer "B.SilkS")
			(hide yes)
			(effects
				(font
					(size 1.27 1.27)
				)
				(justify mirror)
			)
		)
		(property "Value" ""
			(at 0 0 90)
			(layer "B.Fab")
			(effects
				(font
					(size 1.27 1.27)
				)
				(justify mirror)
			)
		)
		(duplicate_pad_numbers_are_jumpers no)
		(fp_line
			(start 1.524 -0.762)
			(end -1.524 -0.762)
			(stroke
				(width 0.1524)
				(type default)
			)
			(layer "B.SilkS")
		)
		(fp_line
			(start -1.524 -0.762)
			(end -1.524 0.762)
			(stroke
				(width 0.1524)
				(type default)
			)
			(layer "B.SilkS")
		)
		(fp_line
			(start 1.524 0.762)
			(end 1.524 -0.762)
			(stroke
				(width 0.1524)
				(type default)
			)
			(layer "B.SilkS")
		)
		(fp_line
			(start -1.524 0.762)
			(end 1.524 0.762)
			(stroke
				(width 0.1524)
				(type default)
			)
			(layer "B.SilkS")
		)
		(fp_line
			(start 1.1049 -0.724916)
			(end 1.1049 0.724916)
			(stroke
				(width 0.1)
				(type default)
			)
			(layer "B.Fab")
		)
		(fp_line
			(start -1.1049 -0.724916)
			(end 1.1049 -0.724916)
			(stroke
				(width 0.1)
				(type default)
			)
			(layer "B.Fab")
		)
		(fp_line
			(start 1.1049 0.724916)
			(end -1.1049 0.724916)
			(stroke
				(width 0.1)
				(type default)
			)
			(layer "B.Fab")
		)
		(fp_line
			(start -1.1049 0.724916)
			(end -1.1049 -0.724916)
			(stroke
				(width 0.1)
				(type default)
			)
			(layer "B.Fab")
		)
		(pad "1" smd rect
			(at 0.889 0 90)
			(size 1.016 1.27)
			(layers "B.Cu" "B.Mask" "B.Paste")
			(net "PVDDCR_CPU0_P1")
		)
		(pad "2" smd rect
			(at -0.889 0 90)
			(size 1.016 1.27)
			(layers "B.Cu" "B.Mask" "B.Paste")
			(net "GND")
		)
	)
	(footprint ""
		(layer "B.Cu")
		(at 59.404504 -408.517344 90)
		(property "Reference" "C6667"
			(at 0 0 90)
			(layer "B.SilkS")
			(hide yes)
			(effects
				(font
					(size 1.27 1.27)
				)
				(justify mirror)
			)
		)
		(property "Value" ""
			(at 0 0 90)
			(layer "B.Fab")
			(effects
				(font
					(size 1.27 1.27)
				)
				(justify mirror)
			)
		)
		(duplicate_pad_numbers_are_jumpers no)
		(fp_line
			(start 0.299974 -0.150114)
			(end -0.299974 -0.150114)
			(stroke
				(width 0.1)
				(type default)
			)
			(layer "B.Fab")
		)
		(fp_line
			(start -0.299974 -0.150114)
			(end -0.299974 0.150114)
			(stroke
				(width 0.1)
				(type default)
			)
			(layer "B.Fab")
		)
		(fp_line
			(start 0.299974 0.150114)
			(end 0.299974 -0.150114)
			(stroke
				(width 0.1)
				(type default)
			)
			(layer "B.Fab")
		)
		(fp_line
			(start -0.299974 0.150114)
			(end 0.299974 0.150114)
			(stroke
				(width 0.1)
				(type default)
			)
			(layer "B.Fab")
		)
		(pad "1" smd rect
			(at 0.2667 0 270)
			(size 0.3048 0.381)
			(layers "B.Cu" "B.Mask" "B.Paste")
			(net "P5E_CPU1_P1_TX_BUF_C_DP<3>")
		)
		(pad "2" smd rect
			(at -0.2667 0 270)
			(size 0.3048 0.381)
			(layers "B.Cu" "B.Mask" "B.Paste")
			(net "P5E_CPU1_P1_TX_BUF_DP<3>")
		)
	)
	(footprint ""
		(layer "B.Cu")
		(at 231.775 -216.662)
		(property "Reference" "R322"
			(at 0 0 0)
			(layer "B.SilkS")
			(hide yes)
			(effects
				(font
					(size 1.27 1.27)
				)
				(justify mirror)
			)
		)
		(property "Value" ""
			(at 0 0 0)
			(layer "B.Fab")
			(effects
				(font
					(size 1.27 1.27)
				)
				(justify mirror)
			)
		)
		(duplicate_pad_numbers_are_jumpers no)
		(fp_line
			(start -0.7874 -0.4064)
			(end -0.7874 0.4064)
			(stroke
				(width 0.1524)
				(type default)
			)
			(layer "B.SilkS")
		)
		(fp_line
			(start -0.7874 0.4064)
			(end 0.7874 0.4064)
			(stroke
				(width 0.1524)
				(type default)
			)
			(layer "B.SilkS")
		)
		(fp_line
			(start 0.7874 -0.4064)
			(end -0.7874 -0.4064)
			(stroke
				(width 0.1524)
				(type default)
			)
			(layer "B.SilkS")
		)
		(fp_line
			(start 0.7874 0.4064)
			(end 0.7874 -0.4064)
			(stroke
				(width 0.1524)
				(type default)
			)
			(layer "B.SilkS")
		)
		(fp_line
			(start -0.67945 -0.3048)
			(end -0.67945 0.3048)
			(stroke
				(width 0.1)
				(type default)
			)
			(layer "B.Fab")
		)
		(fp_line
			(start -0.67945 0.3048)
			(end -0.120396 0.3048)
			(stroke
				(width 0.1)
				(type default)
			)
			(layer "B.Fab")
		)
		(fp_line
			(start -0.12065 -0.3048)
			(end -0.67945 -0.3048)
			(stroke
				(width 0.1)
				(type default)
			)
			(layer "B.Fab")
		)
		(fp_line
			(start -0.12065 -0.2794)
			(end -0.12065 -0.3048)
			(stroke
				(width 0.1)
				(type default)
			)
			(layer "B.Fab")
		)
		(fp_line
			(start -0.120396 0.2794)
			(end 0.12065 0.2794)
			(stroke
				(width 0.1)
				(type default)
			)
			(layer "B.Fab")
		)
		(fp_line
			(start -0.120396 0.3048)
			(end -0.120396 0.2794)
			(stroke
				(width 0.1)
				(type default)
			)
			(layer "B.Fab")
		)
		(fp_line
			(start 0.12065 -0.305054)
			(end 0.12065 -0.2794)
			(stroke
				(width 0.1)
				(type default)
			)
			(layer "B.Fab")
		)
		(fp_line
			(start 0.12065 -0.2794)
			(end -0.12065 -0.2794)
			(stroke
				(width 0.1)
				(type default)
			)
			(layer "B.Fab")
		)
		(fp_line
			(start 0.12065 0.2794)
			(end 0.12065 0.3048)
			(stroke
				(width 0.1)
				(type default)
			)
			(layer "B.Fab")
		)
		(fp_line
			(start 0.12065 0.3048)
			(end 0.67945 0.3048)
			(stroke
				(width 0.1)
				(type default)
			)
			(layer "B.Fab")
		)
		(fp_line
			(start 0.67945 -0.305054)
			(end 0.12065 -0.305054)
			(stroke
				(width 0.1)
				(type default)
			)
			(layer "B.Fab")
		)
		(fp_line
			(start 0.67945 0.3048)
			(end 0.67945 -0.305054)
			(stroke
				(width 0.1)
				(type default)
			)
			(layer "B.Fab")
		)
		(pad "1" smd circle
			(at 0.40005 0 180)
			(size 0 0)
			(layers "B.Cu" "B.Mask" "B.Paste")
			(net "PVDD11_S3_P0")
		)
		(pad "2" smd circle
			(at -0.40005 0 180)
			(size 0 0)
			(layers "B.Cu" "B.Mask" "B.Paste")
			(net "SMB_CPU0_CPU1_APML_BUF2_SCL_R2")
		)
	)
	(footprint ""
		(layer "B.Cu")
		(at 90.209878 -139.80541 180)
		(property "Reference" "C5012"
			(at 0 0 0)
			(layer "B.SilkS")
			(hide yes)
			(effects
				(font
					(size 1.27 1.27)
				)
				(justify mirror)
			)
		)
		(property "Value" ""
			(at 0 0 0)
			(layer "B.Fab")
			(effects
				(font
					(size 1.27 1.27)
				)
				(justify mirror)
			)
		)
		(duplicate_pad_numbers_are_jumpers no)
		(fp_line
			(start 0.7874 0.4064)
			(end 0.7874 -0.4064)
			(stroke
				(width 0.1524)
				(type default)
			)
			(layer "B.SilkS")
		)
		(fp_line
			(start 0.7874 -0.4064)
			(end -0.7874 -0.4064)
			(stroke
				(width 0.1524)
				(type default)
			)
			(layer "B.SilkS")
		)
		(fp_line
			(start -0.7874 0.4064)
			(end 0.7874 0.4064)
			(stroke
				(width 0.1524)
				(type default)
			)
			(layer "B.SilkS")
		)
		(fp_line
			(start -0.7874 -0.4064)
			(end -0.7874 0.4064)
			(stroke
				(width 0.1524)
				(type default)
			)
			(layer "B.SilkS")
		)
		(fp_line
			(start 0.67945 0.3048)
			(end 0.67945 -0.305054)
			(stroke
				(width 0.1)
				(type default)
			)
			(layer "B.Fab")
		)
		(fp_line
			(start 0.67945 -0.305054)
			(end 0.12065 -0.305054)
			(stroke
				(width 0.1)
				(type default)
			)
			(layer "B.Fab")
		)
		(fp_line
			(start 0.12065 0.3048)
			(end 0.67945 0.3048)
			(stroke
				(width 0.1)
				(type default)
			)
			(layer "B.Fab")
		)
		(fp_line
			(start 0.12065 0.2794)
			(end 0.12065 0.3048)
			(stroke
				(width 0.1)
				(type default)
			)
			(layer "B.Fab")
		)
		(fp_line
			(start 0.12065 -0.2794)
			(end -0.12065 -0.2794)
			(stroke
				(width 0.1)
				(type default)
			)
			(layer "B.Fab")
		)
		(fp_line
			(start 0.12065 -0.305054)
			(end 0.12065 -0.2794)
			(stroke
				(width 0.1)
				(type default)
			)
			(layer "B.Fab")
		)
		(fp_line
			(start -0.120396 0.3048)
			(end -0.120396 0.2794)
			(stroke
				(width 0.1)
				(type default)
			)
			(layer "B.Fab")
		)
		(fp_line
			(start -0.120396 0.2794)
			(end 0.12065 0.2794)
			(stroke
				(width 0.1)
				(type default)
			)
			(layer "B.Fab")
		)
		(fp_line
			(start -0.12065 -0.2794)
			(end -0.12065 -0.3048)
			(stroke
				(width 0.1)
				(type default)
			)
			(layer "B.Fab")
		)
		(fp_line
			(start -0.12065 -0.3048)
			(end -0.67945 -0.3048)
			(stroke
				(width 0.1)
				(type default)
			)
			(layer "B.Fab")
		)
		(fp_line
			(start -0.67945 0.3048)
			(end -0.120396 0.3048)
			(stroke
				(width 0.1)
				(type default)
			)
			(layer "B.Fab")
		)
		(fp_line
			(start -0.67945 -0.3048)
			(end -0.67945 0.3048)
			(stroke
				(width 0.1)
				(type default)
			)
			(layer "B.Fab")
		)
		(pad "1" smd circle
			(at 0.40005 0)
			(size 0 0)
			(layers "B.Cu" "B.Mask" "B.Paste")
			(net "PVDDCR_CPU0_P1_PMALERT")
		)
		(pad "2" smd circle
			(at -0.40005 0)
			(size 0 0)
			(layers "B.Cu" "B.Mask" "B.Paste")
			(net "GND")
		)
	)
	(footprint ""
		(layer "B.Cu")
		(at 164.403532 -432.37658 -90)
		(property "Reference" "C14"
			(at 0 0 90)
			(layer "B.SilkS")
			(hide yes)
			(effects
				(font
					(size 1.27 1.27)
				)
				(justify mirror)
			)
		)
		(property "Value" ""
			(at 0 0 90)
			(layer "B.Fab")
			(effects
				(font
					(size 1.27 1.27)
				)
				(justify mirror)
			)
		)
		(duplicate_pad_numbers_are_jumpers no)
		(fp_line
			(start -0.7874 0.4064)
			(end 0.7874 0.4064)
			(stroke
				(width 0.1524)
				(type default)
			)
			(layer "B.SilkS")
		)
		(fp_line
			(start 0.7874 0.4064)
			(end 0.7874 -0.4064)
			(stroke
				(width 0.1524)
				(type default)
			)
			(layer "B.SilkS")
		)
		(fp_line
			(start -0.7874 -0.4064)
			(end -0.7874 0.4064)
			(stroke
				(width 0.1524)
				(type default)
			)
			(layer "B.SilkS")
		)
		(fp_line
			(start 0.7874 -0.4064)
			(end -0.7874 -0.4064)
			(stroke
				(width 0.1524)
				(type default)
			)
			(layer "B.SilkS")
		)
		(fp_line
			(start -0.67945 0.3048)
			(end -0.120396 0.3048)
			(stroke
				(width 0.1)
				(type default)
			)
			(layer "B.Fab")
		)
		(fp_line
			(start -0.120396 0.3048)
			(end -0.120396 0.2794)
			(stroke
				(width 0.1)
				(type default)
			)
			(layer "B.Fab")
		)
		(fp_line
			(start 0.12065 0.3048)
			(end 0.67945 0.3048)
			(stroke
				(width 0.1)
				(type default)
			)
			(layer "B.Fab")
		)
		(fp_line
			(start 0.67945 0.3048)
			(end 0.67945 -0.305054)
			(stroke
				(width 0.1)
				(type default)
			)
			(layer "B.Fab")
		)
		(fp_line
			(start -0.120396 0.2794)
			(end 0.12065 0.2794)
			(stroke
				(width 0.1)
				(type default)
			)
			(layer "B.Fab")
		)
		(fp_line
			(start 0.12065 0.2794)
			(end 0.12065 0.3048)
			(stroke
				(width 0.1)
				(type default)
			)
			(layer "B.Fab")
		)
		(fp_line
			(start -0.12065 -0.2794)
			(end -0.12065 -0.3048)
			(stroke
				(width 0.1)
				(type default)
			)
			(layer "B.Fab")
		)
		(fp_line
			(start 0.12065 -0.2794)
			(end -0.12065 -0.2794)
			(stroke
				(width 0.1)
				(type default)
			)
			(layer "B.Fab")
		)
		(fp_line
			(start -0.67945 -0.3048)
			(end -0.67945 0.3048)
			(stroke
				(width 0.1)
				(type default)
			)
			(layer "B.Fab")
		)
		(fp_line
			(start -0.12065 -0.3048)
			(end -0.67945 -0.3048)
			(stroke
				(width 0.1)
				(type default)
			)
			(layer "B.Fab")
		)
		(fp_line
			(start 0.12065 -0.305054)
			(end 0.12065 -0.2794)
			(stroke
				(width 0.1)
				(type default)
			)
			(layer "B.Fab")
		)
		(fp_line
			(start 0.67945 -0.305054)
			(end 0.12065 -0.305054)
			(stroke
				(width 0.1)
				(type default)
			)
			(layer "B.Fab")
		)
		(pad "1" smd circle
			(at 0.40005 0 90)
			(size 0 0)
			(layers "B.Cu" "B.Mask" "B.Paste")
			(net "GPU_3V3IO_RSVD1_FFU_ISO")
		)
		(pad "2" smd circle
			(at -0.40005 0 90)
			(size 0 0)
			(layers "B.Cu" "B.Mask" "B.Paste")
			(net "GND")
		)
	)
	(footprint ""
		(layer "B.Cu")
		(at 154.218894 -390.560052 90)
		(property "Reference" "C414"
			(at 0 0 90)
			(layer "B.SilkS")
			(hide yes)
			(effects
				(font
					(size 1.27 1.27)
				)
				(justify mirror)
			)
		)
		(property "Value" ""
			(at 0 0 90)
			(layer "B.Fab")
			(effects
				(font
					(size 1.27 1.27)
				)
				(justify mirror)
			)
		)
		(duplicate_pad_numbers_are_jumpers no)
		(fp_line
			(start 0.7874 -0.4064)
			(end -0.7874 -0.4064)
			(stroke
				(width 0.1524)
				(type default)
			)
			(layer "B.SilkS")
		)
		(fp_line
			(start -0.7874 -0.4064)
			(end -0.7874 0.4064)
			(stroke
				(width 0.1524)
				(type default)
			)
			(layer "B.SilkS")
		)
		(fp_line
			(start 0.7874 0.4064)
			(end 0.7874 -0.4064)
			(stroke
				(width 0.1524)
				(type default)
			)
			(layer "B.SilkS")
		)
		(fp_line
			(start -0.7874 0.4064)
			(end 0.7874 0.4064)
			(stroke
				(width 0.1524)
				(type default)
			)
			(layer "B.SilkS")
		)
		(fp_line
			(start 0.67945 -0.305054)
			(end 0.12065 -0.305054)
			(stroke
				(width 0.1)
				(type default)
			)
			(layer "B.Fab")
		)
		(fp_line
			(start 0.12065 -0.305054)
			(end 0.12065 -0.2794)
			(stroke
				(width 0.1)
				(type default)
			)
			(layer "B.Fab")
		)
		(fp_line
			(start -0.12065 -0.3048)
			(end -0.67945 -0.3048)
			(stroke
				(width 0.1)
				(type default)
			)
			(layer "B.Fab")
		)
		(fp_line
			(start -0.67945 -0.3048)
			(end -0.67945 0.3048)
			(stroke
				(width 0.1)
				(type default)
			)
			(layer "B.Fab")
		)
		(fp_line
			(start 0.12065 -0.2794)
			(end -0.12065 -0.2794)
			(stroke
				(width 0.1)
				(type default)
			)
			(layer "B.Fab")
		)
		(fp_line
			(start -0.12065 -0.2794)
			(end -0.12065 -0.3048)
			(stroke
				(width 0.1)
				(type default)
			)
			(layer "B.Fab")
		)
		(fp_line
			(start 0.12065 0.2794)
			(end 0.12065 0.3048)
			(stroke
				(width 0.1)
				(type default)
			)
			(layer "B.Fab")
		)
		(fp_line
			(start -0.120396 0.2794)
			(end 0.12065 0.2794)
			(stroke
				(width 0.1)
				(type default)
			)
			(layer "B.Fab")
		)
		(fp_line
			(start 0.67945 0.3048)
			(end 0.67945 -0.305054)
			(stroke
				(width 0.1)
				(type default)
			)
			(layer "B.Fab")
		)
		(fp_line
			(start 0.12065 0.3048)
			(end 0.67945 0.3048)
			(stroke
				(width 0.1)
				(type default)
			)
			(layer "B.Fab")
		)
		(fp_line
			(start -0.120396 0.3048)
			(end -0.120396 0.2794)
			(stroke
				(width 0.1)
				(type default)
			)
			(layer "B.Fab")
		)
		(fp_line
			(start -0.67945 0.3048)
			(end -0.120396 0.3048)
			(stroke
				(width 0.1)
				(type default)
			)
			(layer "B.Fab")
		)
		(pad "1" smd circle
			(at 0.40005 0 270)
			(size 0 0)
			(layers "B.Cu" "B.Mask" "B.Paste")
			(net "P0V9_CPU1_RT_2D")
		)
		(pad "2" smd circle
			(at -0.40005 0 270)
			(size 0 0)
			(layers "B.Cu" "B.Mask" "B.Paste")
			(net "GND")
		)
	)
	(footprint ""
		(layer "B.Cu")
		(at 234.315 -215.186514 180)
		(property "Reference" "R274"
			(at 0 0 0)
			(layer "B.SilkS")
			(hide yes)
			(effects
				(font
					(size 1.27 1.27)
				)
				(justify mirror)
			)
		)
		(property "Value" ""
			(at 0 0 0)
			(layer "B.Fab")
			(effects
				(font
					(size 1.27 1.27)
				)
				(justify mirror)
			)
		)
		(duplicate_pad_numbers_are_jumpers no)
		(fp_line
			(start 0.7874 0.4064)
			(end 0.7874 -0.4064)
			(stroke
				(width 0.1524)
				(type default)
			)
			(layer "B.SilkS")
		)
		(fp_line
			(start 0.7874 -0.4064)
			(end -0.7874 -0.4064)
			(stroke
				(width 0.1524)
				(type default)
			)
			(layer "B.SilkS")
		)
		(fp_line
			(start -0.7874 0.4064)
			(end 0.7874 0.4064)
			(stroke
				(width 0.1524)
				(type default)
			)
			(layer "B.SilkS")
		)
		(fp_line
			(start -0.7874 -0.4064)
			(end -0.7874 0.4064)
			(stroke
				(width 0.1524)
				(type default)
			)
			(layer "B.SilkS")
		)
		(fp_line
			(start 0.67945 0.3048)
			(end 0.67945 -0.305054)
			(stroke
				(width 0.1)
				(type default)
			)
			(layer "B.Fab")
		)
		(fp_line
			(start 0.67945 -0.305054)
			(end 0.12065 -0.305054)
			(stroke
				(width 0.1)
				(type default)
			)
			(layer "B.Fab")
		)
		(fp_line
			(start 0.12065 0.3048)
			(end 0.67945 0.3048)
			(stroke
				(width 0.1)
				(type default)
			)
			(layer "B.Fab")
		)
		(fp_line
			(start 0.12065 0.2794)
			(end 0.12065 0.3048)
			(stroke
				(width 0.1)
				(type default)
			)
			(layer "B.Fab")
		)
		(fp_line
			(start 0.12065 -0.2794)
			(end -0.12065 -0.2794)
			(stroke
				(width 0.1)
				(type default)
			)
			(layer "B.Fab")
		)
		(fp_line
			(start 0.12065 -0.305054)
			(end 0.12065 -0.2794)
			(stroke
				(width 0.1)
				(type default)
			)
			(layer "B.Fab")
		)
		(fp_line
			(start -0.120396 0.3048)
			(end -0.120396 0.2794)
			(stroke
				(width 0.1)
				(type default)
			)
			(layer "B.Fab")
		)
		(fp_line
			(start -0.120396 0.2794)
			(end 0.12065 0.2794)
			(stroke
				(width 0.1)
				(type default)
			)
			(layer "B.Fab")
		)
		(fp_line
			(start -0.12065 -0.2794)
			(end -0.12065 -0.3048)
			(stroke
				(width 0.1)
				(type default)
			)
			(layer "B.Fab")
		)
		(fp_line
			(start -0.12065 -0.3048)
			(end -0.67945 -0.3048)
			(stroke
				(width 0.1)
				(type default)
			)
			(layer "B.Fab")
		)
		(fp_line
			(start -0.67945 0.3048)
			(end -0.120396 0.3048)
			(stroke
				(width 0.1)
				(type default)
			)
			(layer "B.Fab")
		)
		(fp_line
			(start -0.67945 -0.3048)
			(end -0.67945 0.3048)
			(stroke
				(width 0.1)
				(type default)
			)
			(layer "B.Fab")
		)
		(pad "1" smd rect
			(at 0.40005 0 180)
			(size 0.4572 0.508)
			(layers "B.Cu" "B.Mask" "B.Paste")
			(net "SMB_CPU0_CPU1_APML_BUF2_SCL_R2")
		)
		(pad "2" smd rect
			(at -0.40005 0 180)
			(size 0.4572 0.508)
			(layers "B.Cu" "B.Mask" "B.Paste")
			(net "SMB_CPU0_CPU1_APML_SCL_R2")
		)
	)
)
